(kicad_pcb
	(version 20260206)
	(generator "pcbnew")
	(generator_version "10.0")
	(general
		(thickness 1.6)
		(legacy_teardrops no)
	)
	(paper "A4")
	(title_block
		(title "Wiwynn_Tioga_Pass_MB.brd")
		(comment 1 "Tioga Pass / footprint 2254 of 4770 (U5D1), pads 3372-3484 of 3647")
	)
	(layers
		(0 "F.Cu" signal "TOP")
		(4 "In1.Cu" signal "L2GND")
		(6 "In2.Cu" signal "L3")
		(8 "In3.Cu" signal "L4GND")
		(10 "In4.Cu" signal "L5")
		(12 "In5.Cu" signal "L6GND")
		(14 "In6.Cu" signal "L7VCC")
		(16 "In7.Cu" signal "L8VCC")
		(18 "In8.Cu" signal "L9GND")
		(20 "In9.Cu" signal "L10")
		(22 "In10.Cu" signal "L11GND")
		(24 "In11.Cu" signal "L12")
		(26 "In12.Cu" signal "L13GND")
		(2 "B.Cu" signal "BOTTOM")
		(9 "F.Adhes" user "F.Adhesive")
		(11 "B.Adhes" user "B.Adhesive")
		(13 "F.Paste" user "Package Geometry/Pastemask Top")
		(15 "B.Paste" user "Package Geometry/Pastemask Bottom")
		(5 "F.SilkS" user "Ref Des/Silkscreen Top")
		(7 "B.SilkS" user "Ref Des/Silkscreen Bottom")
		(1 "F.Mask" user "Board Geometry/Soldermask Top")
		(3 "B.Mask" user "Board Geometry/Soldermask Bottom")
		(17 "Dwgs.User" user "User.Drawings")
		(19 "Cmts.User" user "User.Comments")
		(21 "Eco1.User" user "User.Eco1")
		(23 "Eco2.User" user "User.Eco2")
		(25 "Edge.Cuts" user "Board Geometry/Outline")
		(27 "Margin" user)
		(31 "F.CrtYd" user "Package Geometry/Place Bound Top")
		(29 "B.CrtYd" user "Package Geometry/Place Bound Bottom")
		(35 "F.Fab" user "Ref Des/Assembly Top")
		(33 "B.Fab" user "Ref Des/Assembly Bottom")
	)
	(footprint ""
		(layer "F.Cu")
		(at 270.000222 -76.550012 180)
		(property "Reference" "U5D1"
			(at 19.124422 31.601918 0)
			(unlocked yes)
			(layer "F.SilkS")
			(effects
				(font
					(size 0.7874 0.5842)
					(thickness 0.1524)
				)
			)
		)
		(property "Value" ""
			(at 0 0 180)
			(layer "F.Fab")
			(effects
				(font
					(size 1.27 1.27)
				)
			)
		)
		(duplicate_pad_numbers_are_jumpers no)
		(pad "P45" smd circle
			(at 2.052066 -20.464526)
			(size 0.508 0.508)
			(layers "F.Cu" "F.Mask" "F.Paste")
			(net "GND")
		)
		(pad "P47" smd circle
			(at 3.769106 -20.464526)
			(size 0.4318 0.4318)
			(layers "F.Cu" "F.Mask" "F.Paste")
			(net "GND")
		)
		(pad "P49" smd circle
			(at 5.485892 -20.464526)
			(size 0.4318 0.4318)
			(layers "F.Cu" "F.Mask" "F.Paste")
			(net "GND")
		)
		(pad "P51" smd circle
			(at 7.202932 -20.464526)
			(size 0.4318 0.4318)
			(layers "F.Cu" "F.Mask" "F.Paste")
			(net "GND")
		)
		(pad "P53" smd circle
			(at 8.919972 -20.464526)
			(size 0.4318 0.4318)
			(layers "F.Cu" "F.Mask" "F.Paste")
			(net "GND")
		)
		(pad "P55" smd circle
			(at 10.637012 -20.464526)
			(size 0.4318 0.4318)
			(layers "F.Cu" "F.Mask" "F.Paste")
			(net "GND")
		)
		(pad "P57" smd circle
			(at 12.354052 -20.464526)
			(size 0.4318 0.4318)
			(layers "F.Cu" "F.Mask" "F.Paste")
			(net "GND")
		)
		(pad "P59" smd circle
			(at 14.071092 -20.464526)
			(size 0.4318 0.4318)
			(layers "F.Cu" "F.Mask" "F.Paste")
			(net "GND")
		)
		(pad "P61" smd circle
			(at 15.787878 -20.464526)
			(size 0.4318 0.4318)
			(layers "F.Cu" "F.Mask" "F.Paste")
			(net "GND")
		)
		(pad "P63" smd circle
			(at 17.504918 -20.464526)
			(size 0.4318 0.4318)
			(layers "F.Cu" "F.Mask" "F.Paste")
			(net "GND")
		)
		(pad "P65" smd circle
			(at 19.221958 -20.464526)
			(size 0.4318 0.4318)
			(layers "F.Cu" "F.Mask" "F.Paste")
			(net "TP_CPU0_RSVD_265")
		)
		(pad "P67" smd circle
			(at 20.938998 -20.464526)
			(size 0.4318 0.4318)
			(layers "F.Cu" "F.Mask" "F.Paste")
			(net "GND")
		)
		(pad "P69" smd circle
			(at 22.656038 -20.464526)
			(size 0.4318 0.4318)
			(layers "F.Cu" "F.Mask" "F.Paste")
			(net "GND")
		)
		(pad "P71" smd circle
			(at 24.373078 -20.464526)
			(size 0.4318 0.4318)
			(layers "F.Cu" "F.Mask" "F.Paste")
			(net "GND")
		)
		(pad "P73" smd circle
			(at 26.090118 -20.464526)
			(size 0.4318 0.4318)
			(layers "F.Cu" "F.Mask" "F.Paste")
			(net "M_A_DQ<27>")
		)
		(pad "P75" smd circle
			(at 27.806904 -20.464526)
			(size 0.4318 0.4318)
			(layers "F.Cu" "F.Mask" "F.Paste")
			(net "M_A_DQS_DP<3>")
		)
		(pad "P77" smd circle
			(at 29.523944 -20.464526)
			(size 0.4318 0.4318)
			(layers "F.Cu" "F.Mask" "F.Paste")
			(net "M_A_DQ<29>")
		)
		(pad "P79" smd circle
			(at 31.240984 -20.464526)
			(size 0.4318 0.4318)
			(layers "F.Cu" "F.Mask" "F.Paste")
			(net "M_A_DQS_DN<2>")
		)
		(pad "P81" smd circle
			(at 32.958024 -20.464526)
			(size 0.4318 0.4318)
			(layers "F.Cu" "F.Mask" "F.Paste")
			(net "GND")
		)
		(pad "P83" smd circle
			(at 34.675064 -20.464526)
			(size 0.4318 0.4318)
			(layers "F.Cu" "F.Mask" "F.Paste")
			(net "GND")
		)
		(pad "P85" smd circle
			(at 36.392104 -20.464526)
			(size 0.4318 0.4318)
			(layers "F.Cu" "F.Mask" "F.Paste")
			(net "M_A_DQS_DP<1>")
		)
		(pad "R2" smd circle
			(at -36.392104 -18.168874)
			(size 0.4318 0.4318)
			(layers "F.Cu" "F.Mask" "F.Paste")
			(net "GND")
		)
		(pad "R4" smd circle
			(at -34.675064 -18.168874)
			(size 0.4318 0.4318)
			(layers "F.Cu" "F.Mask" "F.Paste")
			(net "GND")
		)
		(pad "R6" smd circle
			(at -32.958024 -18.168874)
			(size 0.4318 0.4318)
			(layers "F.Cu" "F.Mask" "F.Paste")
			(net "UPI_CPU1_CPU0_P1P1_DP<19>")
		)
		(pad "R8" smd circle
			(at -31.240984 -18.168874)
			(size 0.4318 0.4318)
			(layers "F.Cu" "F.Mask" "F.Paste")
			(net "UPI_CPU1_CPU0_P1P1_DP<16>")
		)
		(pad "R10" smd circle
			(at -29.523944 -18.168874)
			(size 0.4318 0.4318)
			(layers "F.Cu" "F.Mask" "F.Paste")
			(net "UPI_CPU1_CPU0_P1P1_DN<14>")
		)
		(pad "R12" smd circle
			(at -27.806904 -18.168874)
			(size 0.4318 0.4318)
			(layers "F.Cu" "F.Mask" "F.Paste")
			(net "UPI_CPU1_CPU0_P1P1_DN<10>")
		)
		(pad "R14" smd circle
			(at -26.090118 -18.168874)
			(size 0.4318 0.4318)
			(layers "F.Cu" "F.Mask" "F.Paste")
			(net "GND")
		)
		(pad "R16" smd circle
			(at -24.373078 -18.168874)
			(size 0.4318 0.4318)
			(layers "F.Cu" "F.Mask" "F.Paste")
			(net "UPI_CPU1_CPU0_P1P1_DN<9>")
		)
		(pad "R18" smd circle
			(at -22.656038 -18.168874)
			(size 0.4318 0.4318)
			(layers "F.Cu" "F.Mask" "F.Paste")
			(net "GND")
		)
		(pad "R20" smd circle
			(at -20.938998 -18.168874)
			(size 0.4318 0.4318)
			(layers "F.Cu" "F.Mask" "F.Paste")
			(net "UPI_CPU1_CPU0_P1P1_DN<5>")
		)
		(pad "R22" smd circle
			(at -19.221958 -18.168874)
			(size 0.4318 0.4318)
			(layers "F.Cu" "F.Mask" "F.Paste")
			(net "GND")
		)
		(pad "R24" smd circle
			(at -17.504918 -18.168874)
			(size 0.4318 0.4318)
			(layers "F.Cu" "F.Mask" "F.Paste")
			(net "M_A_DQS_DP<7>")
		)
		(pad "R26" smd circle
			(at -15.787878 -18.168874)
			(size 0.4318 0.4318)
			(layers "F.Cu" "F.Mask" "F.Paste")
			(net "GND")
		)
		(pad "R28" smd circle
			(at -14.071092 -18.168874)
			(size 0.4318 0.4318)
			(layers "F.Cu" "F.Mask" "F.Paste")
			(net "GND")
		)
		(pad "R30" smd circle
			(at -12.354052 -18.168874)
			(size 0.4318 0.4318)
			(layers "F.Cu" "F.Mask" "F.Paste")
			(net "M_A_DQS_DN<6>")
		)
		(pad "R32" smd circle
			(at -10.637012 -18.168874)
			(size 0.4318 0.4318)
			(layers "F.Cu" "F.Mask" "F.Paste")
			(net "GND")
		)
		(pad "R34" smd circle
			(at -8.919972 -18.168874)
			(size 0.4318 0.4318)
			(layers "F.Cu" "F.Mask" "F.Paste")
			(net "GND")
		)
		(pad "R36" smd circle
			(at -7.202932 -18.168874)
			(size 0.4318 0.4318)
			(layers "F.Cu" "F.Mask" "F.Paste")
			(net "M_A_DQS_DN<5>")
		)
		(pad "R38" smd circle
			(at -5.485892 -18.168874)
			(size 0.4318 0.4318)
			(layers "F.Cu" "F.Mask" "F.Paste")
			(net "GND")
		)
		(pad "R40" smd circle
			(at -3.769106 -18.168874)
			(size 0.4318 0.4318)
			(layers "F.Cu" "F.Mask" "F.Paste")
			(net "GND")
		)
		(pad "R42" smd circle
			(at -2.052066 -18.168874)
			(size 0.4318 0.4318)
			(layers "F.Cu" "F.Mask" "F.Paste")
			(net "M_B_DQS_DP<4>")
		)
		(pad "R46" smd circle
			(at 2.910586 -19.968972)
			(size 0.4318 0.4318)
			(layers "F.Cu" "F.Mask" "F.Paste")
			(net "M_B_CS_N<7>")
		)
		(pad "R48" smd circle
			(at 4.627626 -19.968972)
			(size 0.4318 0.4318)
			(layers "F.Cu" "F.Mask" "F.Paste")
			(net "M_B_ODT<1>")
		)
		(pad "R50" smd circle
			(at 6.344412 -19.968972)
			(size 0.4318 0.4318)
			(layers "F.Cu" "F.Mask" "F.Paste")
			(net "M_B_CS_N<1>")
		)
		(pad "R52" smd circle
			(at 8.061452 -19.968972)
			(size 0.4318 0.4318)
			(layers "F.Cu" "F.Mask" "F.Paste")
			(net "M_B_MA<16>")
		)
		(pad "R54" smd circle
			(at 9.778492 -19.968972)
			(size 0.4318 0.4318)
			(layers "F.Cu" "F.Mask" "F.Paste")
			(net "M_B_CLK_DN<1>")
		)
		(pad "R56" smd circle
			(at 11.495532 -19.968972)
			(size 0.4318 0.4318)
			(layers "F.Cu" "F.Mask" "F.Paste")
			(net "M_B_CLK_DN<3>")
		)
		(pad "R58" smd circle
			(at 13.212572 -19.968972)
			(size 0.4318 0.4318)
			(layers "F.Cu" "F.Mask" "F.Paste")
			(net "M_B_MA<5>")
		)
		(pad "R60" smd circle
			(at 14.929612 -19.968972)
			(size 0.4318 0.4318)
			(layers "F.Cu" "F.Mask" "F.Paste")
			(net "M_B_MA<11>")
		)
		(pad "R62" smd circle
			(at 16.646398 -19.968972)
			(size 0.4318 0.4318)
			(layers "F.Cu" "F.Mask" "F.Paste")
			(net "TP_CPU0_RSVD_264")
		)
		(pad "R64" smd circle
			(at 18.363438 -19.968972)
			(size 0.4318 0.4318)
			(layers "F.Cu" "F.Mask" "F.Paste")
			(net "M_B_CKE<1>")
		)
		(pad "R66" smd circle
			(at 20.080478 -19.968972)
			(size 0.4318 0.4318)
			(layers "F.Cu" "F.Mask" "F.Paste")
			(net "TP_CPU0_RSVD_263")
		)
		(pad "R68" smd circle
			(at 21.797518 -19.968972)
			(size 0.4318 0.4318)
			(layers "F.Cu" "F.Mask" "F.Paste")
			(net "GND")
		)
		(pad "R70" smd circle
			(at 23.514558 -19.968972)
			(size 0.4318 0.4318)
			(layers "F.Cu" "F.Mask" "F.Paste")
			(net "M_C_DQ<18>")
		)
		(pad "R72" smd circle
			(at 25.231598 -19.968972)
			(size 0.4318 0.4318)
			(layers "F.Cu" "F.Mask" "F.Paste")
			(net "GND")
		)
		(pad "R74" smd circle
			(at 26.948384 -19.968972)
			(size 0.4318 0.4318)
			(layers "F.Cu" "F.Mask" "F.Paste")
			(net "M_A_DQ<31>")
		)
		(pad "R76" smd circle
			(at 28.665424 -19.968972)
			(size 0.4318 0.4318)
			(layers "F.Cu" "F.Mask" "F.Paste")
			(net "M_A_DQ<25>")
		)
		(pad "R78" smd circle
			(at 30.382464 -19.968972)
			(size 0.4318 0.4318)
			(layers "F.Cu" "F.Mask" "F.Paste")
			(net "GND")
		)
		(pad "R80" smd circle
			(at 32.099504 -19.968972)
			(size 0.4318 0.4318)
			(layers "F.Cu" "F.Mask" "F.Paste")
			(net "M_A_DQS_DP<2>")
		)
		(pad "R82" smd circle
			(at 33.816544 -19.968972)
			(size 0.4318 0.4318)
			(layers "F.Cu" "F.Mask" "F.Paste")
			(net "M_A_DQ<22>")
		)
		(pad "R84" smd circle
			(at 35.533584 -19.968972)
			(size 0.4318 0.4318)
			(layers "F.Cu" "F.Mask" "F.Paste")
			(net "M_A_DQS_DN<1>")
		)
		(pad "R86" smd custom
			(at 37.250624 -19.968972 270)
			(size 0.10795 0.10795)
			(layers "F.Cu" "F.Mask" "F.Paste")
			(net "GND")
			(options
				(clearance outline)
				(anchor circle)
			)
			(primitives
				(gr_poly
					(pts
						(arc
							(start 0.2159 -0.0381)
							(mid 0 -0.254)
							(end -0.2159 -0.0381)
						)
						(arc
							(start -0.2159 0.0381)
							(mid 0 0.254)
							(end 0.2159 0.0381)
						)
					)
					(width 0)
					(fill yes)
				)
			)
		)
		(pad "T1" smd custom
			(at -37.250624 -17.673574 90)
			(size 0.10795 0.10795)
			(layers "F.Cu" "F.Mask" "F.Paste")
			(net "UPI_CPU0_CPU1_P0P0_DP<18>")
			(options
				(clearance outline)
				(anchor circle)
			)
			(primitives
				(gr_poly
					(pts
						(arc
							(start 0.2159 -0.0381)
							(mid 0 -0.254)
							(end -0.2159 -0.0381)
						)
						(arc
							(start -0.2159 0.0381)
							(mid 0 0.254)
							(end 0.2159 0.0381)
						)
					)
					(width 0)
					(fill yes)
				)
			)
		)
		(pad "T3" smd circle
			(at -35.533584 -17.673574)
			(size 0.4318 0.4318)
			(layers "F.Cu" "F.Mask" "F.Paste")
			(net "PVCCIO_CPU0")
		)
		(pad "T5" smd circle
			(at -33.816544 -17.673574)
			(size 0.4318 0.4318)
			(layers "F.Cu" "F.Mask" "F.Paste")
			(net "UPI_CPU1_CPU0_P1P1_DN<19>")
		)
		(pad "T7" smd circle
			(at -32.099504 -17.673574)
			(size 0.4318 0.4318)
			(layers "F.Cu" "F.Mask" "F.Paste")
			(net "UPI_CPU1_CPU0_P1P1_DP<18>")
		)
		(pad "T9" smd circle
			(at -30.382464 -17.673574)
			(size 0.4318 0.4318)
			(layers "F.Cu" "F.Mask" "F.Paste")
			(net "UPI_CPU1_CPU0_P1P1_DN<16>")
		)
		(pad "T11" smd circle
			(at -28.665424 -17.673574)
			(size 0.4318 0.4318)
			(layers "F.Cu" "F.Mask" "F.Paste")
			(net "UPI_CPU1_CPU0_P1P1_DP<13>")
		)
		(pad "T13" smd circle
			(at -26.948384 -17.673574)
			(size 0.4318 0.4318)
			(layers "F.Cu" "F.Mask" "F.Paste")
			(net "GND")
		)
		(pad "T15" smd circle
			(at -25.231598 -17.673574)
			(size 0.4318 0.4318)
			(layers "F.Cu" "F.Mask" "F.Paste")
			(net "UPI_CPU1_CPU0_P1P1_DP<9>")
		)
		(pad "T17" smd circle
			(at -23.514558 -17.673574)
			(size 0.4318 0.4318)
			(layers "F.Cu" "F.Mask" "F.Paste")
			(net "GND")
		)
		(pad "T19" smd circle
			(at -21.797518 -17.673574)
			(size 0.4318 0.4318)
			(layers "F.Cu" "F.Mask" "F.Paste")
			(net "UPI_CPU1_CPU0_P1P1_DP<4>")
		)
		(pad "T21" smd circle
			(at -20.080478 -17.673574)
			(size 0.4318 0.4318)
			(layers "F.Cu" "F.Mask" "F.Paste")
			(net "UPI_CPU1_CPU0_P1P1_DP<3>")
		)
		(pad "T23" smd circle
			(at -18.363438 -17.673574)
			(size 0.4318 0.4318)
			(layers "F.Cu" "F.Mask" "F.Paste")
			(net "M_A_DQ<59>")
		)
		(pad "T25" smd circle
			(at -16.646398 -17.673574)
			(size 0.4318 0.4318)
			(layers "F.Cu" "F.Mask" "F.Paste")
			(net "GND")
		)
		(pad "T27" smd circle
			(at -14.929612 -17.673574)
			(size 0.4318 0.4318)
			(layers "F.Cu" "F.Mask" "F.Paste")
			(net "M_B_DQS_DN<16>")
		)
		(pad "T29" smd circle
			(at -13.212572 -17.673574)
			(size 0.4318 0.4318)
			(layers "F.Cu" "F.Mask" "F.Paste")
			(net "GND")
		)
		(pad "T31" smd circle
			(at -11.495532 -17.673574)
			(size 0.4318 0.4318)
			(layers "F.Cu" "F.Mask" "F.Paste")
			(net "GND")
		)
		(pad "T33" smd circle
			(at -9.778492 -17.673574)
			(size 0.4318 0.4318)
			(layers "F.Cu" "F.Mask" "F.Paste")
			(net "M_C_DQS_DN<14>")
		)
		(pad "T35" smd circle
			(at -8.061452 -17.673574)
			(size 0.4318 0.4318)
			(layers "F.Cu" "F.Mask" "F.Paste")
			(net "GND")
		)
		(pad "T37" smd circle
			(at -6.344412 -17.673574)
			(size 0.4318 0.4318)
			(layers "F.Cu" "F.Mask" "F.Paste")
			(net "GND")
		)
		(pad "T39" smd circle
			(at -4.627626 -17.673574)
			(size 0.4318 0.4318)
			(layers "F.Cu" "F.Mask" "F.Paste")
			(net "M_C_DQS_DN<13>")
		)
		(pad "T41" smd circle
			(at -2.910586 -17.673574)
			(size 0.4318 0.4318)
			(layers "F.Cu" "F.Mask" "F.Paste")
			(net "GND")
		)
		(pad "T43" smd circle
			(at -1.193546 -17.673574)
			(size 0.4318 0.4318)
			(layers "F.Cu" "F.Mask" "F.Paste")
			(net "M_B_DQ<37>")
		)
		(pad "T45" smd circle
			(at 2.052066 -19.473926)
			(size 0.508 0.508)
			(layers "F.Cu" "F.Mask" "F.Paste")
			(net "M_C_CS_N<6>")
		)
		(pad "T47" smd circle
			(at 3.769106 -19.473926)
			(size 0.4318 0.4318)
			(layers "F.Cu" "F.Mask" "F.Paste")
			(net "M_B_ODT<3>")
		)
		(pad "T49" smd circle
			(at 5.485892 -19.473926)
			(size 0.4318 0.4318)
			(layers "F.Cu" "F.Mask" "F.Paste")
			(net "M_B_CS_N<5>")
		)
		(pad "T51" smd circle
			(at 7.202932 -19.473926)
			(size 0.4318 0.4318)
			(layers "F.Cu" "F.Mask" "F.Paste")
			(net "M_B_MA<14>")
		)
		(pad "T53" smd circle
			(at 8.919972 -19.473926)
			(size 0.4318 0.4318)
			(layers "F.Cu" "F.Mask" "F.Paste")
			(net "M_B_BA<0>")
		)
		(pad "T55" smd circle
			(at 10.637012 -19.473926)
			(size 0.4318 0.4318)
			(layers "F.Cu" "F.Mask" "F.Paste")
			(net "M_B_CLK_DP<1>")
		)
		(pad "T57" smd circle
			(at 12.354052 -19.473926)
			(size 0.4318 0.4318)
			(layers "F.Cu" "F.Mask" "F.Paste")
			(net "M_B_CLK_DP<3>")
		)
		(pad "T59" smd circle
			(at 14.071092 -19.473926)
			(size 0.4318 0.4318)
			(layers "F.Cu" "F.Mask" "F.Paste")
			(net "M_B_MA<6>")
		)
		(pad "T61" smd circle
			(at 15.787878 -19.473926)
			(size 0.4318 0.4318)
			(layers "F.Cu" "F.Mask" "F.Paste")
			(net "M_B_MA<12>")
		)
		(pad "T63" smd circle
			(at 17.504918 -19.473926)
			(size 0.4318 0.4318)
			(layers "F.Cu" "F.Mask" "F.Paste")
			(net "M_B_ACT_N")
		)
		(pad "T65" smd circle
			(at 19.221958 -19.473926)
			(size 0.4318 0.4318)
			(layers "F.Cu" "F.Mask" "F.Paste")
			(net "GND")
		)
		(pad "T67" smd circle
			(at 20.938998 -19.473926)
			(size 0.4318 0.4318)
			(layers "F.Cu" "F.Mask" "F.Paste")
			(net "TP_CPU0_RSVD_262")
		)
		(pad "T69" smd circle
			(at 22.656038 -19.473926)
			(size 0.4318 0.4318)
			(layers "F.Cu" "F.Mask" "F.Paste")
			(net "M_C_DQ<19>")
		)
		(pad "T71" smd circle
			(at 24.373078 -19.473926)
			(size 0.4318 0.4318)
			(layers "F.Cu" "F.Mask" "F.Paste")
			(net "M_C_DQ<22>")
		)
		(pad "T73" smd circle
			(at 26.090118 -19.473926)
			(size 0.4318 0.4318)
			(layers "F.Cu" "F.Mask" "F.Paste")
			(net "GND")
		)
		(pad "T75" smd circle
			(at 27.806904 -19.473926)
			(size 0.4318 0.4318)
			(layers "F.Cu" "F.Mask" "F.Paste")
			(net "M_A_DQS_DN<3>")
		)
		(pad "T77" smd circle
			(at 29.523944 -19.473926)
			(size 0.4318 0.4318)
			(layers "F.Cu" "F.Mask" "F.Paste")
			(net "GND")
		)
		(pad "T79" smd circle
			(at 31.240984 -19.473926)
			(size 0.4318 0.4318)
			(layers "F.Cu" "F.Mask" "F.Paste")
			(net "M_A_DQ<17>")
		)
		(pad "T81" smd circle
			(at 32.958024 -19.473926)
			(size 0.4318 0.4318)
			(layers "F.Cu" "F.Mask" "F.Paste")
			(net "M_A_DQS_DP<11>")
		)
		(pad "T83" smd circle
			(at 34.675064 -19.473926)
			(size 0.4318 0.4318)
			(layers "F.Cu" "F.Mask" "F.Paste")
			(net "GND")
		)
		(pad "T85" smd circle
			(at 36.392104 -19.473926)
			(size 0.4318 0.4318)
			(layers "F.Cu" "F.Mask" "F.Paste")
			(net "GND")
		)
		(pad "U2" smd circle
			(at -36.392104 -17.178528)
			(size 0.4318 0.4318)
			(layers "F.Cu" "F.Mask" "F.Paste")
			(net "GND")
		)
		(pad "U4" smd circle
			(at -34.675064 -17.178528)
			(size 0.4318 0.4318)
			(layers "F.Cu" "F.Mask" "F.Paste")
			(net "GND")
		)
		(pad "U6" smd circle
			(at -32.958024 -17.178528)
			(size 0.4318 0.4318)
			(layers "F.Cu" "F.Mask" "F.Paste")
			(net "GND")
		)
		(pad "U8" smd circle
			(at -31.240984 -17.178528)
			(size 0.4318 0.4318)
			(layers "F.Cu" "F.Mask" "F.Paste")
			(net "UPI_CPU1_CPU0_P1P1_DP<17>")
		)
		(pad "U10" smd circle
			(at -29.523944 -17.178528)
			(size 0.4318 0.4318)
			(layers "F.Cu" "F.Mask" "F.Paste")
			(net "UPI_CPU1_CPU0_P1P1_DP<14>")
		)
		(pad "U12" smd circle
			(at -27.806904 -17.178528)
			(size 0.4318 0.4318)
			(layers "F.Cu" "F.Mask" "F.Paste")
			(net "UPI_CPU1_CPU0_P1P1_DN<13>")
		)
		(pad "U14" smd circle
			(at -26.090118 -17.178528)
			(size 0.4318 0.4318)
			(layers "F.Cu" "F.Mask" "F.Paste")
			(net "PVCCIO_CPU0")
		)
	)
)
